(kicad_pcb
	(version 20260206)
	(generator "pcbnew")
	(generator_version "10.0")
	(general
		(thickness 1.6)
		(legacy_teardrops no)
	)
	(paper "A4")
	(title_block
		(title "Bryce Canyon_F.DPB_16315-1-OCP.brd")
		(comment 1 "Bryce Canyon / footprints 594-600 of 2223")
	)
	(layers
		(0 "F.Cu" signal "TOP")
		(4 "In1.Cu" signal "L2GND")
		(6 "In2.Cu" signal "L3")
		(8 "In3.Cu" signal "L4GND")
		(10 "In4.Cu" signal "L5")
		(12 "In5.Cu" signal "L6VCC")
		(14 "In6.Cu" signal "L7VCC")
		(16 "In7.Cu" signal "L8")
		(18 "In8.Cu" signal "L9GND")
		(20 "In9.Cu" signal "L10")
		(22 "In10.Cu" signal "L11GND")
		(2 "B.Cu" signal "BOTTOM")
		(9 "F.Adhes" user "F.Adhesive")
		(11 "B.Adhes" user "B.Adhesive")
		(13 "F.Paste" user "Package Geometry/Pastemask Top")
		(15 "B.Paste" user "Package Geometry/Pastemask Bottom")
		(5 "F.SilkS" user "Ref Des/Silkscreen Top")
		(7 "B.SilkS" user "Ref Des/Silkscreen Bottom")
		(1 "F.Mask" user "Board Geometry/Soldermask Top")
		(3 "B.Mask" user "Board Geometry/Soldermask Bottom")
		(17 "Dwgs.User" user "User.Drawings")
		(19 "Cmts.User" user "User.Comments")
		(21 "Eco1.User" user "User.Eco1")
		(23 "Eco2.User" user "User.Eco2")
		(25 "Edge.Cuts" user "Board Geometry/Outline")
		(27 "Margin" user)
		(31 "F.CrtYd" user "Package Geometry/Place Bound Top")
		(29 "B.CrtYd" user "Package Geometry/Place Bound Bottom")
		(35 "F.Fab" user "Ref Des/Assembly Top")
		(33 "B.Fab" user "Ref Des/Assembly Bottom")
	)
	(footprint ""
		(layer "F.Cu")
		(at 257.1496 -13.7668 90)
		(property "Reference" "R1007"
			(at 0 0 90)
			(layer "F.SilkS")
			(hide yes)
			(effects
				(font
					(size 1.27 1.27)
				)
			)
		)
		(property "Value" "100KR2F-L1-GP"
			(at 0.064008 -3.993896 90)
			(unlocked yes)
			(layer "F.Fab")
			(hide yes)
			(effects
				(font
					(size 1.016 1.016)
					(thickness 0.1524)
				)
			)
		)
		(property "Device Type" "R402H16"
			(at 0.064008 -5.517896 90)
			(unlocked yes)
			(layer "F.Fab")
			(hide yes)
			(effects
				(font
					(size 1.016 1.016)
					(thickness 0.1524)
				)
			)
		)
		(duplicate_pad_numbers_are_jumpers no)
		(fp_line
			(start 0.508 -0.9398)
			(end -0.508 -0.9398)
			(stroke
				(width 0.1524)
				(type default)
			)
			(layer "F.SilkS")
		)
		(fp_line
			(start -0.508 -0.9398)
			(end -0.508 0.9398)
			(stroke
				(width 0.1524)
				(type default)
			)
			(layer "F.SilkS")
		)
		(fp_rect
			(start -0.508 0.9398)
			(end 0.508 -0.9398)
			(stroke
				(width 0)
				(type default)
			)
			(fill no)
			(layer "F.CrtYd")
		)
		(fp_rect
			(start -0.508 0.9398)
			(end 0.508 -0.9398)
			(stroke
				(width 0)
				(type default)
			)
			(fill no)
			(layer "F.Fab")
		)
		(pad "1" smd custom
			(at 0 -0.4445 90)
			(size 0.1397 0.1397)
			(layers "F.Cu" "F.Mask" "F.Paste")
			(net "PCIE_COMP_A_TO_IOM_A_RST_3")
			(options
				(clearance outline)
				(anchor circle)
			)
			(primitives
				(gr_poly
					(pts
						(arc
							(start -0.1778 -0.2794)
							(mid -0.249642 -0.249642)
							(end -0.2794 -0.1778)
						)
						(arc
							(start -0.2794 0.1778)
							(mid -0.249642 0.249642)
							(end -0.1778 0.2794)
						)
						(arc
							(start 0.1778 0.2794)
							(mid 0.249642 0.249642)
							(end 0.2794 0.1778)
						)
						(arc
							(start 0.2794 -0.1778)
							(mid 0.249642 -0.249642)
							(end 0.1778 -0.2794)
						)
					)
					(width 0)
					(fill yes)
				)
			)
		)
		(pad "2" smd custom
			(at 0 0.4445 90)
			(size 0.1397 0.1397)
			(layers "F.Cu" "F.Mask" "F.Paste")
			(net "GND")
			(options
				(clearance outline)
				(anchor circle)
			)
			(primitives
				(gr_poly
					(pts
						(arc
							(start -0.1778 -0.2794)
							(mid -0.249642 -0.249642)
							(end -0.2794 -0.1778)
						)
						(arc
							(start -0.2794 0.1778)
							(mid -0.249642 0.249642)
							(end -0.1778 0.2794)
						)
						(arc
							(start 0.1778 0.2794)
							(mid 0.249642 0.249642)
							(end 0.2794 0.1778)
						)
						(arc
							(start 0.2794 -0.1778)
							(mid 0.249642 -0.249642)
							(end 0.1778 -0.2794)
						)
					)
					(width 0)
					(fill yes)
				)
			)
		)
	)
	(footprint ""
		(layer "F.Cu")
		(at 175.6664 -161.649918 180)
		(property "Reference" "D17"
			(at 0 0 180)
			(layer "F.SilkS")
			(hide yes)
			(effects
				(font
					(size 1.27 1.27)
				)
			)
		)
		(property "Value" "RB551V30-GP"
			(at 0 -6.7818 180)
			(unlocked yes)
			(layer "F.Fab")
			(hide yes)
			(effects
				(font
					(size 1.016 1.016)
					(thickness 0.1524)
				)
			)
		)
		(property "Device Type" "SOD323AKH38"
			(at 0 -8.6868 180)
			(unlocked yes)
			(layer "F.Fab")
			(hide yes)
			(effects
				(font
					(size 1.016 1.016)
					(thickness 0.1524)
				)
			)
		)
		(duplicate_pad_numbers_are_jumpers no)
		(fp_line
			(start 0.889 2.159)
			(end -0.889 2.159)
			(stroke
				(width 0.1524)
				(type default)
			)
			(layer "F.SilkS")
		)
		(fp_line
			(start 0.889 -1.9304)
			(end 0.889 2.159)
			(stroke
				(width 0.1524)
				(type default)
			)
			(layer "F.SilkS")
		)
		(fp_line
			(start 0.762 2.0574)
			(end -0.762 2.0574)
			(stroke
				(width 0.508)
				(type default)
			)
			(layer "F.SilkS")
		)
		(fp_line
			(start -0.889 2.159)
			(end -0.889 -1.9304)
			(stroke
				(width 0.1524)
				(type default)
			)
			(layer "F.SilkS")
		)
		(fp_line
			(start -0.889 -1.9304)
			(end 0.889 -1.9304)
			(stroke
				(width 0.1524)
				(type default)
			)
			(layer "F.SilkS")
		)
		(fp_rect
			(start -1.016 2.3114)
			(end 1.016 -2.0066)
			(stroke
				(width 0)
				(type default)
			)
			(fill no)
			(layer "F.CrtYd")
		)
		(fp_poly
			(pts
				(xy -1.016 -2.0066) (xy 1.016 -2.0066) (xy 1.016 2.3114) (xy -1.016 2.3114)
			)
			(stroke
				(width 0)
				(type default)
			)
			(fill no)
			(layer "F.Fab")
		)
		(pad "A" smd rect
			(at 0 -1.143 180)
			(size 0.5588 1.016)
			(layers "F.Cu" "F.Mask" "F.Paste")
			(net "SW_HDD_R17")
		)
		(pad "K" smd rect
			(at 0 1.143 180)
			(size 0.5588 1.016)
			(layers "F.Cu" "F.Mask" "F.Paste")
			(net "SW_HDD_N17")
		)
	)
	(footprint ""
		(layer "F.Cu")
		(at 237.128812 -252.93828 90)
		(property "Reference" "C10"
			(at 0 0 90)
			(layer "F.SilkS")
			(hide yes)
			(effects
				(font
					(size 1.27 1.27)
				)
			)
		)
		(property "Value" "SCD1U16V2KX-3GP"
			(at 1.1811 -2.7051 90)
			(unlocked yes)
			(layer "F.Fab")
			(hide yes)
			(effects
				(font
					(size 1.016 1.016)
					(thickness 0.1524)
				)
			)
		)
		(property "Device Type" "C402H22"
			(at 1.1811 -4.2291 90)
			(unlocked yes)
			(layer "F.Fab")
			(hide yes)
			(effects
				(font
					(size 1.016 1.016)
					(thickness 0.1524)
				)
			)
		)
		(duplicate_pad_numbers_are_jumpers no)
		(fp_rect
			(start -0.4318 0.9525)
			(end 0.4318 -0.9525)
			(stroke
				(width 0)
				(type default)
			)
			(fill no)
			(layer "F.CrtYd")
		)
		(fp_rect
			(start -0.4318 0.9525)
			(end 0.4318 -0.9525)
			(stroke
				(width 0)
				(type default)
			)
			(fill no)
			(layer "F.Fab")
		)
		(pad "1" smd custom
			(at 0 -0.4445 90)
			(size 0.1524 0.1524)
			(layers "F.Cu" "F.Mask" "F.Paste")
			(net "P3V3_STBY_A")
			(options
				(clearance outline)
				(anchor circle)
			)
			(primitives
				(gr_poly
					(pts
						(arc
							(start 0.3048 -0.2032)
							(mid 0.275042 -0.275042)
							(end 0.2032 -0.3048)
						)
						(arc
							(start -0.2032 -0.3048)
							(mid -0.275042 -0.275042)
							(end -0.3048 -0.2032)
						)
						(arc
							(start -0.3048 0.2032)
							(mid -0.275042 0.275042)
							(end -0.2032 0.3048)
						)
						(arc
							(start 0.2032 0.3048)
							(mid 0.275042 0.275042)
							(end 0.3048 0.2032)
						)
					)
					(width 0)
					(fill yes)
				)
			)
		)
		(pad "2" smd custom
			(at 0 0.4445 90)
			(size 0.1524 0.1524)
			(layers "F.Cu" "F.Mask" "F.Paste")
			(net "GND")
			(options
				(clearance outline)
				(anchor circle)
			)
			(primitives
				(gr_poly
					(pts
						(arc
							(start 0.3048 -0.2032)
							(mid 0.275042 -0.275042)
							(end 0.2032 -0.3048)
						)
						(arc
							(start -0.2032 -0.3048)
							(mid -0.275042 -0.275042)
							(end -0.3048 -0.2032)
						)
						(arc
							(start -0.3048 0.2032)
							(mid -0.275042 0.275042)
							(end -0.2032 0.3048)
						)
						(arc
							(start 0.2032 0.3048)
							(mid 0.275042 0.275042)
							(end 0.3048 0.2032)
						)
					)
					(width 0)
					(fill yes)
				)
			)
		)
	)
	(footprint ""
		(layer "F.Cu")
		(at 276.2758 -284.7086 180)
		(property "Reference" "R110"
			(at 0 0 180)
			(layer "F.SilkS")
			(hide yes)
			(effects
				(font
					(size 1.27 1.27)
				)
			)
		)
		(property "Value" "4K7R2F-GP"
			(at 0.064008 -3.993896 180)
			(unlocked yes)
			(layer "F.Fab")
			(hide yes)
			(effects
				(font
					(size 1.016 1.016)
					(thickness 0.1524)
				)
			)
		)
		(property "Device Type" "R402H16"
			(at 0.064008 -5.517896 180)
			(unlocked yes)
			(layer "F.Fab")
			(hide yes)
			(effects
				(font
					(size 1.016 1.016)
					(thickness 0.1524)
				)
			)
		)
		(duplicate_pad_numbers_are_jumpers no)
		(fp_line
			(start 0.508 -0.9398)
			(end -0.508 -0.9398)
			(stroke
				(width 0.1524)
				(type default)
			)
			(layer "F.SilkS")
		)
		(fp_line
			(start -0.508 -0.9398)
			(end -0.508 0.9398)
			(stroke
				(width 0.1524)
				(type default)
			)
			(layer "F.SilkS")
		)
		(fp_rect
			(start -0.508 0.9398)
			(end 0.508 -0.9398)
			(stroke
				(width 0)
				(type default)
			)
			(fill no)
			(layer "F.CrtYd")
		)
		(fp_rect
			(start -0.508 0.9398)
			(end 0.508 -0.9398)
			(stroke
				(width 0)
				(type default)
			)
			(fill no)
			(layer "F.Fab")
		)
		(pad "1" smd custom
			(at 0 -0.4445 180)
			(size 0.1397 0.1397)
			(layers "F.Cu" "F.Mask" "F.Paste")
			(net "IO_EXP1_HDD_FAULT_A0")
			(options
				(clearance outline)
				(anchor circle)
			)
			(primitives
				(gr_poly
					(pts
						(arc
							(start -0.1778 -0.2794)
							(mid -0.249642 -0.249642)
							(end -0.2794 -0.1778)
						)
						(arc
							(start -0.2794 0.1778)
							(mid -0.249642 0.249642)
							(end -0.1778 0.2794)
						)
						(arc
							(start 0.1778 0.2794)
							(mid 0.249642 0.249642)
							(end 0.2794 0.1778)
						)
						(arc
							(start 0.2794 -0.1778)
							(mid 0.249642 -0.249642)
							(end 0.1778 -0.2794)
						)
					)
					(width 0)
					(fill yes)
				)
			)
		)
		(pad "2" smd custom
			(at 0 0.4445 180)
			(size 0.1397 0.1397)
			(layers "F.Cu" "F.Mask" "F.Paste")
			(net "GND")
			(options
				(clearance outline)
				(anchor circle)
			)
			(primitives
				(gr_poly
					(pts
						(arc
							(start -0.1778 -0.2794)
							(mid -0.249642 -0.249642)
							(end -0.2794 -0.1778)
						)
						(arc
							(start -0.2794 0.1778)
							(mid -0.249642 0.249642)
							(end -0.1778 0.2794)
						)
						(arc
							(start 0.1778 0.2794)
							(mid 0.249642 0.249642)
							(end 0.2794 0.1778)
						)
						(arc
							(start 0.2794 -0.1778)
							(mid 0.249642 -0.249642)
							(end 0.1778 -0.2794)
						)
					)
					(width 0)
					(fill yes)
				)
			)
		)
	)
	(footprint ""
		(layer "F.Cu")
		(at 452.277988 -256.3495 -90)
		(property "Reference" "R1248"
			(at 0 0 270)
			(layer "F.SilkS")
			(hide yes)
			(effects
				(font
					(size 1.27 1.27)
				)
			)
		)
		(property "Value" "10KR2F-2-GP"
			(at 0.064008 -3.993896 270)
			(unlocked yes)
			(layer "F.Fab")
			(hide yes)
			(effects
				(font
					(size 1.016 1.016)
					(thickness 0.1524)
				)
			)
		)
		(property "Device Type" "R402H16"
			(at 0.064008 -5.517896 270)
			(unlocked yes)
			(layer "F.Fab")
			(hide yes)
			(effects
				(font
					(size 1.016 1.016)
					(thickness 0.1524)
				)
			)
		)
		(duplicate_pad_numbers_are_jumpers no)
		(fp_line
			(start -0.508 -0.9398)
			(end -0.508 0.9398)
			(stroke
				(width 0.1524)
				(type default)
			)
			(layer "F.SilkS")
		)
		(fp_line
			(start 0.508 -0.9398)
			(end -0.508 -0.9398)
			(stroke
				(width 0.1524)
				(type default)
			)
			(layer "F.SilkS")
		)
		(fp_rect
			(start -0.508 0.9398)
			(end 0.508 -0.9398)
			(stroke
				(width 0)
				(type default)
			)
			(fill no)
			(layer "F.CrtYd")
		)
		(fp_rect
			(start -0.508 0.9398)
			(end 0.508 -0.9398)
			(stroke
				(width 0)
				(type default)
			)
			(fill no)
			(layer "F.Fab")
		)
		(pad "1" smd custom
			(at 0 -0.4445 270)
			(size 0.1397 0.1397)
			(layers "F.Cu" "F.Mask" "F.Paste")
			(net "P5V_A_3")
			(options
				(clearance outline)
				(anchor circle)
			)
			(primitives
				(gr_poly
					(pts
						(arc
							(start -0.1778 -0.2794)
							(mid -0.249642 -0.249642)
							(end -0.2794 -0.1778)
						)
						(arc
							(start -0.2794 0.1778)
							(mid -0.249642 0.249642)
							(end -0.1778 0.2794)
						)
						(arc
							(start 0.1778 0.2794)
							(mid 0.249642 0.249642)
							(end 0.2794 0.1778)
						)
						(arc
							(start 0.2794 -0.1778)
							(mid 0.249642 -0.249642)
							(end 0.1778 -0.2794)
						)
					)
					(width 0)
					(fill yes)
				)
			)
		)
		(pad "2" smd custom
			(at 0 0.4445 270)
			(size 0.1397 0.1397)
			(layers "F.Cu" "F.Mask" "F.Paste")
			(net "P5V_A_3_PGOOD")
			(options
				(clearance outline)
				(anchor circle)
			)
			(primitives
				(gr_poly
					(pts
						(arc
							(start -0.1778 -0.2794)
							(mid -0.249642 -0.249642)
							(end -0.2794 -0.1778)
						)
						(arc
							(start -0.2794 0.1778)
							(mid -0.249642 0.249642)
							(end -0.1778 0.2794)
						)
						(arc
							(start 0.1778 0.2794)
							(mid 0.249642 0.249642)
							(end 0.2794 0.1778)
						)
						(arc
							(start 0.2794 -0.1778)
							(mid 0.249642 -0.249642)
							(end 0.1778 -0.2794)
						)
					)
					(width 0)
					(fill yes)
				)
			)
		)
	)
	(footprint ""
		(layer "F.Cu")
		(at 381.36195 -177.169318 90)
		(property "Reference" "R590"
			(at 0 0 90)
			(layer "F.SilkS")
			(hide yes)
			(effects
				(font
					(size 1.27 1.27)
				)
			)
		)
		(property "Value" "10KR2F-2-GP"
			(at 0.064008 -3.993896 90)
			(unlocked yes)
			(layer "F.Fab")
			(hide yes)
			(effects
				(font
					(size 1.016 1.016)
					(thickness 0.1524)
				)
			)
		)
		(property "Device Type" "R402H16"
			(at 0.064008 -5.517896 90)
			(unlocked yes)
			(layer "F.Fab")
			(hide yes)
			(effects
				(font
					(size 1.016 1.016)
					(thickness 0.1524)
				)
			)
		)
		(duplicate_pad_numbers_are_jumpers no)
		(fp_line
			(start 0.508 -0.9398)
			(end -0.508 -0.9398)
			(stroke
				(width 0.1524)
				(type default)
			)
			(layer "F.SilkS")
		)
		(fp_line
			(start -0.508 -0.9398)
			(end -0.508 0.9398)
			(stroke
				(width 0.1524)
				(type default)
			)
			(layer "F.SilkS")
		)
		(fp_rect
			(start -0.508 0.9398)
			(end 0.508 -0.9398)
			(stroke
				(width 0)
				(type default)
			)
			(fill no)
			(layer "F.CrtYd")
		)
		(fp_rect
			(start -0.508 0.9398)
			(end 0.508 -0.9398)
			(stroke
				(width 0)
				(type default)
			)
			(fill no)
			(layer "F.Fab")
		)
		(pad "1" smd custom
			(at 0 -0.4445 90)
			(size 0.1397 0.1397)
			(layers "F.Cu" "F.Mask" "F.Paste")
			(net "P3V3_STBY_A")
			(options
				(clearance outline)
				(anchor circle)
			)
			(primitives
				(gr_poly
					(pts
						(arc
							(start -0.1778 -0.2794)
							(mid -0.249642 -0.249642)
							(end -0.2794 -0.1778)
						)
						(arc
							(start -0.2794 0.1778)
							(mid -0.249642 0.249642)
							(end -0.1778 0.2794)
						)
						(arc
							(start 0.1778 0.2794)
							(mid 0.249642 0.249642)
							(end 0.2794 0.1778)
						)
						(arc
							(start 0.2794 -0.1778)
							(mid 0.249642 -0.249642)
							(end 0.1778 -0.2794)
						)
					)
					(width 0)
					(fill yes)
				)
			)
		)
		(pad "2" smd custom
			(at 0 0.4445 90)
			(size 0.1397 0.1397)
			(layers "F.Cu" "F.Mask" "F.Paste")
			(net "HDD_PRSNT_20")
			(options
				(clearance outline)
				(anchor circle)
			)
			(primitives
				(gr_poly
					(pts
						(arc
							(start -0.1778 -0.2794)
							(mid -0.249642 -0.249642)
							(end -0.2794 -0.1778)
						)
						(arc
							(start -0.2794 0.1778)
							(mid -0.249642 0.249642)
							(end -0.1778 0.2794)
						)
						(arc
							(start 0.1778 0.2794)
							(mid 0.249642 0.249642)
							(end 0.2794 0.1778)
						)
						(arc
							(start 0.2794 -0.1778)
							(mid 0.249642 -0.249642)
							(end 0.1778 -0.2794)
						)
					)
					(width 0)
					(fill yes)
				)
			)
		)
	)
	(footprint ""
		(layer "F.Cu")
		(at 140.532866 -131.656074 180)
		(property "Reference" "R1051"
			(at 0 0 180)
			(layer "F.SilkS")
			(hide yes)
			(effects
				(font
					(size 1.27 1.27)
				)
			)
		)
		(property "Value" "10KR2F-2-GP"
			(at 0.064008 -3.993896 180)
			(unlocked yes)
			(layer "F.Fab")
			(hide yes)
			(effects
				(font
					(size 1.016 1.016)
					(thickness 0.1524)
				)
			)
		)
		(property "Device Type" "R402H16"
			(at 0.064008 -5.517896 180)
			(unlocked yes)
			(layer "F.Fab")
			(hide yes)
			(effects
				(font
					(size 1.016 1.016)
					(thickness 0.1524)
				)
			)
		)
		(duplicate_pad_numbers_are_jumpers no)
		(fp_line
			(start 0.508 -0.9398)
			(end -0.508 -0.9398)
			(stroke
				(width 0.1524)
				(type default)
			)
			(layer "F.SilkS")
		)
		(fp_line
			(start -0.508 -0.9398)
			(end -0.508 0.9398)
			(stroke
				(width 0.1524)
				(type default)
			)
			(layer "F.SilkS")
		)
		(fp_rect
			(start -0.508 0.9398)
			(end 0.508 -0.9398)
			(stroke
				(width 0)
				(type default)
			)
			(fill no)
			(layer "F.CrtYd")
		)
		(fp_rect
			(start -0.508 0.9398)
			(end 0.508 -0.9398)
			(stroke
				(width 0)
				(type default)
			)
			(fill no)
			(layer "F.Fab")
		)
		(pad "1" smd custom
			(at 0 -0.4445 180)
			(size 0.1397 0.1397)
			(layers "F.Cu" "F.Mask" "F.Paste")
			(net "P12V_A_COMP")
			(options
				(clearance outline)
				(anchor circle)
			)
			(primitives
				(gr_poly
					(pts
						(arc
							(start -0.1778 -0.2794)
							(mid -0.249642 -0.249642)
							(end -0.2794 -0.1778)
						)
						(arc
							(start -0.2794 0.1778)
							(mid -0.249642 0.249642)
							(end -0.1778 0.2794)
						)
						(arc
							(start 0.1778 0.2794)
							(mid 0.249642 0.249642)
							(end 0.2794 0.1778)
						)
						(arc
							(start 0.2794 -0.1778)
							(mid 0.249642 -0.249642)
							(end 0.1778 -0.2794)
						)
					)
					(width 0)
					(fill yes)
				)
			)
		)
		(pad "2" smd custom
			(at 0 0.4445 180)
			(size 0.1397 0.1397)
			(layers "F.Cu" "F.Mask" "F.Paste")
			(net "COMP_A_PGOOD")
			(options
				(clearance outline)
				(anchor circle)
			)
			(primitives
				(gr_poly
					(pts
						(arc
							(start -0.1778 -0.2794)
							(mid -0.249642 -0.249642)
							(end -0.2794 -0.1778)
						)
						(arc
							(start -0.2794 0.1778)
							(mid -0.249642 0.249642)
							(end -0.1778 0.2794)
						)
						(arc
							(start 0.1778 0.2794)
							(mid 0.249642 0.249642)
							(end 0.2794 0.1778)
						)
						(arc
							(start 0.2794 -0.1778)
							(mid 0.249642 -0.249642)
							(end 0.1778 -0.2794)
						)
					)
					(width 0)
					(fill yes)
				)
			)
		)
	)
)
